(kicad_pcb
	(version 20260206)
	(generator "pcbnew")
	(generator_version "10.0")
	(general
		(thickness 1.6)
		(legacy_teardrops no)
	)
	(paper "A4")
	(title_block
		(title "12092022_DA0F0TMDCD0_F0T_Management_Board_D_brd_V3_OCP.brd")
		(comment 1 "Grand Teton / footprints 1178-1183 of 1440")
	)
	(layers
		(0 "F.Cu" signal "TOP")
		(4 "In1.Cu" signal "GND")
		(6 "In2.Cu" signal "IN1")
		(8 "In3.Cu" signal "GND1")
		(10 "In4.Cu" signal "IN2")
		(12 "In5.Cu" signal "VCC")
		(14 "In6.Cu" signal "VCC1")
		(16 "In7.Cu" signal "IN3")
		(18 "In8.Cu" signal "GND2")
		(20 "In9.Cu" signal "IN4")
		(22 "In10.Cu" signal "GND3")
		(2 "B.Cu" signal "BOTTOM")
		(9 "F.Adhes" user "F.Adhesive")
		(11 "B.Adhes" user "B.Adhesive")
		(13 "F.Paste" user "Package Geometry/Pastemask Top")
		(15 "B.Paste" user "Package Geometry/Pastemask Bottom")
		(5 "F.SilkS" user "Ref Des/Silkscreen Top")
		(7 "B.SilkS" user "Ref Des/Silkscreen Bottom")
		(1 "F.Mask" user "Board Geometry/Soldermask Top")
		(3 "B.Mask" user "Board Geometry/Soldermask Bottom")
		(17 "Dwgs.User" user "User.Drawings")
		(19 "Cmts.User" user "User.Comments")
		(21 "Eco1.User" user "User.Eco1")
		(23 "Eco2.User" user "User.Eco2")
		(25 "Edge.Cuts" user "Board Geometry/Outline")
		(27 "Margin" user)
		(31 "F.CrtYd" user "Package Geometry/Place Bound Top")
		(29 "B.CrtYd" user "Package Geometry/Place Bound Bottom")
		(35 "F.Fab" user "Ref Des/Assembly Top")
		(33 "B.Fab" user "Ref Des/Assembly Bottom")
	)
	(footprint ""
		(layer "B.Cu")
		(at 69.342 -43.307)
		(property "Reference" "L11"
			(at 0 0 0)
			(layer "B.SilkS")
			(hide yes)
			(effects
				(font
					(size 1.27 1.27)
				)
				(justify mirror)
			)
		)
		(property "Value" ""
			(at 0 0 0)
			(layer "B.Fab")
			(effects
				(font
					(size 1.27 1.27)
				)
				(justify mirror)
			)
		)
		(duplicate_pad_numbers_are_jumpers no)
		(fp_line
			(start -1.27 0.5842)
			(end -1.27 -0.5842)
			(stroke
				(width 0.1524)
				(type default)
			)
			(layer "B.SilkS")
		)
		(fp_line
			(start -1.27 0.5842)
			(end 1.27 0.5842)
			(stroke
				(width 0.1524)
				(type default)
			)
			(layer "B.SilkS")
		)
		(fp_line
			(start -0.127 0.5842)
			(end -0.127 -0.5842)
			(stroke
				(width 0.1524)
				(type default)
			)
			(layer "B.SilkS")
		)
		(fp_line
			(start 0.127 0.5842)
			(end 0.127 -0.5842)
			(stroke
				(width 0.1524)
				(type default)
			)
			(layer "B.SilkS")
		)
		(fp_line
			(start 1.27 -0.5842)
			(end -1.27 -0.5842)
			(stroke
				(width 0.1524)
				(type default)
			)
			(layer "B.SilkS")
		)
		(fp_line
			(start 1.27 -0.5588)
			(end 1.27 -0.5842)
			(stroke
				(width 0.1524)
				(type default)
			)
			(layer "B.SilkS")
		)
		(fp_line
			(start 1.27 0.5842)
			(end 1.27 -0.5842)
			(stroke
				(width 0.1524)
				(type default)
			)
			(layer "B.SilkS")
		)
		(fp_line
			(start -1.1938 -0.406654)
			(end -1.1938 0.4064)
			(stroke
				(width 0.1)
				(type default)
			)
			(layer "B.Fab")
		)
		(fp_line
			(start -1.1938 0.4064)
			(end -0.9144 0.4064)
			(stroke
				(width 0.1)
				(type default)
			)
			(layer "B.Fab")
		)
		(fp_line
			(start -0.9144 -0.508)
			(end -0.9144 -0.406654)
			(stroke
				(width 0.1)
				(type default)
			)
			(layer "B.Fab")
		)
		(fp_line
			(start -0.9144 -0.406654)
			(end -1.1938 -0.406654)
			(stroke
				(width 0.1)
				(type default)
			)
			(layer "B.Fab")
		)
		(fp_line
			(start -0.9144 0.4064)
			(end -0.9144 0.508)
			(stroke
				(width 0.1)
				(type default)
			)
			(layer "B.Fab")
		)
		(fp_line
			(start -0.9144 0.508)
			(end 0.9144 0.508)
			(stroke
				(width 0.1)
				(type default)
			)
			(layer "B.Fab")
		)
		(fp_line
			(start 0.9144 -0.508)
			(end -0.9144 -0.508)
			(stroke
				(width 0.1)
				(type default)
			)
			(layer "B.Fab")
		)
		(fp_line
			(start 0.9144 -0.406654)
			(end 0.9144 -0.508)
			(stroke
				(width 0.1)
				(type default)
			)
			(layer "B.Fab")
		)
		(fp_line
			(start 0.9144 0.406654)
			(end 1.194308 0.406654)
			(stroke
				(width 0.1)
				(type default)
			)
			(layer "B.Fab")
		)
		(fp_line
			(start 0.9144 0.508)
			(end 0.9144 0.406654)
			(stroke
				(width 0.1)
				(type default)
			)
			(layer "B.Fab")
		)
		(fp_line
			(start 1.194308 -0.406654)
			(end 0.9144 -0.406654)
			(stroke
				(width 0.1)
				(type default)
			)
			(layer "B.Fab")
		)
		(fp_line
			(start 1.194308 0.406654)
			(end 1.194308 -0.406654)
			(stroke
				(width 0.1)
				(type default)
			)
			(layer "B.Fab")
		)
		(pad "1" smd rect
			(at 0.7366 0 270)
			(size 0.7112 0.8128)
			(layers "B.Cu" "B.Mask" "B.Paste")
			(net "P1V2_AUX")
		)
		(pad "2" smd rect
			(at -0.7366 0 270)
			(size 0.7112 0.8128)
			(layers "B.Cu" "B.Mask" "B.Paste")
			(net "P1V2_STBY_MVDD_CK")
		)
	)
	(footprint ""
		(layer "B.Cu")
		(at 58.77941 -30.867604 -90)
		(property "Reference" "R254"
			(at 0 0 90)
			(layer "B.SilkS")
			(hide yes)
			(effects
				(font
					(size 1.27 1.27)
				)
				(justify mirror)
			)
		)
		(property "Value" ""
			(at 0 0 90)
			(layer "B.Fab")
			(effects
				(font
					(size 1.27 1.27)
				)
				(justify mirror)
			)
		)
		(duplicate_pad_numbers_are_jumpers no)
		(fp_line
			(start -0.7874 0.4064)
			(end 0.7874 0.4064)
			(stroke
				(width 0.1524)
				(type default)
			)
			(layer "B.SilkS")
		)
		(fp_line
			(start 0.7874 0.4064)
			(end 0.7874 -0.4064)
			(stroke
				(width 0.1524)
				(type default)
			)
			(layer "B.SilkS")
		)
		(fp_line
			(start -0.7874 -0.4064)
			(end -0.7874 0.4064)
			(stroke
				(width 0.1524)
				(type default)
			)
			(layer "B.SilkS")
		)
		(fp_line
			(start 0.7874 -0.4064)
			(end -0.7874 -0.4064)
			(stroke
				(width 0.1524)
				(type default)
			)
			(layer "B.SilkS")
		)
		(fp_line
			(start -0.67945 0.3048)
			(end -0.120396 0.3048)
			(stroke
				(width 0.1)
				(type default)
			)
			(layer "B.Fab")
		)
		(fp_line
			(start -0.120396 0.3048)
			(end -0.120396 0.2794)
			(stroke
				(width 0.1)
				(type default)
			)
			(layer "B.Fab")
		)
		(fp_line
			(start 0.12065 0.3048)
			(end 0.67945 0.3048)
			(stroke
				(width 0.1)
				(type default)
			)
			(layer "B.Fab")
		)
		(fp_line
			(start 0.67945 0.3048)
			(end 0.67945 -0.305054)
			(stroke
				(width 0.1)
				(type default)
			)
			(layer "B.Fab")
		)
		(fp_line
			(start -0.120396 0.2794)
			(end 0.12065 0.2794)
			(stroke
				(width 0.1)
				(type default)
			)
			(layer "B.Fab")
		)
		(fp_line
			(start 0.12065 0.2794)
			(end 0.12065 0.3048)
			(stroke
				(width 0.1)
				(type default)
			)
			(layer "B.Fab")
		)
		(fp_line
			(start -0.12065 -0.2794)
			(end -0.12065 -0.3048)
			(stroke
				(width 0.1)
				(type default)
			)
			(layer "B.Fab")
		)
		(fp_line
			(start 0.12065 -0.2794)
			(end -0.12065 -0.2794)
			(stroke
				(width 0.1)
				(type default)
			)
			(layer "B.Fab")
		)
		(fp_line
			(start -0.67945 -0.3048)
			(end -0.67945 0.3048)
			(stroke
				(width 0.1)
				(type default)
			)
			(layer "B.Fab")
		)
		(fp_line
			(start -0.12065 -0.3048)
			(end -0.67945 -0.3048)
			(stroke
				(width 0.1)
				(type default)
			)
			(layer "B.Fab")
		)
		(fp_line
			(start 0.12065 -0.305054)
			(end 0.12065 -0.2794)
			(stroke
				(width 0.1)
				(type default)
			)
			(layer "B.Fab")
		)
		(fp_line
			(start 0.67945 -0.305054)
			(end 0.12065 -0.305054)
			(stroke
				(width 0.1)
				(type default)
			)
			(layer "B.Fab")
		)
		(pad "1" smd circle
			(at 0.40005 0 90)
			(size 0 0)
			(layers "B.Cu" "B.Mask" "B.Paste")
			(net "P3V3_AUX")
		)
		(pad "2" smd circle
			(at -0.40005 0 90)
			(size 0 0)
			(layers "B.Cu" "B.Mask" "B.Paste")
			(net "SMB_BMC_MM6_SCL")
		)
	)
	(footprint ""
		(layer "B.Cu")
		(at 29.3624 -30.35935 -90)
		(property "Reference" "C207"
			(at 0 0 90)
			(layer "B.SilkS")
			(hide yes)
			(effects
				(font
					(size 1.27 1.27)
				)
				(justify mirror)
			)
		)
		(property "Value" ""
			(at 0 0 90)
			(layer "B.Fab")
			(effects
				(font
					(size 1.27 1.27)
				)
				(justify mirror)
			)
		)
		(duplicate_pad_numbers_are_jumpers no)
		(fp_line
			(start -0.7874 0.4064)
			(end 0.7874 0.4064)
			(stroke
				(width 0.1524)
				(type default)
			)
			(layer "B.SilkS")
		)
		(fp_line
			(start 0.7874 0.4064)
			(end 0.7874 -0.4064)
			(stroke
				(width 0.1524)
				(type default)
			)
			(layer "B.SilkS")
		)
		(fp_line
			(start -0.7874 -0.4064)
			(end -0.7874 0.4064)
			(stroke
				(width 0.1524)
				(type default)
			)
			(layer "B.SilkS")
		)
		(fp_line
			(start 0.7874 -0.4064)
			(end -0.7874 -0.4064)
			(stroke
				(width 0.1524)
				(type default)
			)
			(layer "B.SilkS")
		)
		(fp_line
			(start -0.67945 0.3048)
			(end -0.120396 0.3048)
			(stroke
				(width 0.1)
				(type default)
			)
			(layer "B.Fab")
		)
		(fp_line
			(start -0.120396 0.3048)
			(end -0.120396 0.2794)
			(stroke
				(width 0.1)
				(type default)
			)
			(layer "B.Fab")
		)
		(fp_line
			(start 0.12065 0.3048)
			(end 0.67945 0.3048)
			(stroke
				(width 0.1)
				(type default)
			)
			(layer "B.Fab")
		)
		(fp_line
			(start 0.67945 0.3048)
			(end 0.67945 -0.305054)
			(stroke
				(width 0.1)
				(type default)
			)
			(layer "B.Fab")
		)
		(fp_line
			(start -0.120396 0.2794)
			(end 0.12065 0.2794)
			(stroke
				(width 0.1)
				(type default)
			)
			(layer "B.Fab")
		)
		(fp_line
			(start 0.12065 0.2794)
			(end 0.12065 0.3048)
			(stroke
				(width 0.1)
				(type default)
			)
			(layer "B.Fab")
		)
		(fp_line
			(start -0.12065 -0.2794)
			(end -0.12065 -0.3048)
			(stroke
				(width 0.1)
				(type default)
			)
			(layer "B.Fab")
		)
		(fp_line
			(start 0.12065 -0.2794)
			(end -0.12065 -0.2794)
			(stroke
				(width 0.1)
				(type default)
			)
			(layer "B.Fab")
		)
		(fp_line
			(start -0.67945 -0.3048)
			(end -0.67945 0.3048)
			(stroke
				(width 0.1)
				(type default)
			)
			(layer "B.Fab")
		)
		(fp_line
			(start -0.12065 -0.3048)
			(end -0.67945 -0.3048)
			(stroke
				(width 0.1)
				(type default)
			)
			(layer "B.Fab")
		)
		(fp_line
			(start 0.12065 -0.305054)
			(end 0.12065 -0.2794)
			(stroke
				(width 0.1)
				(type default)
			)
			(layer "B.Fab")
		)
		(fp_line
			(start 0.67945 -0.305054)
			(end 0.12065 -0.305054)
			(stroke
				(width 0.1)
				(type default)
			)
			(layer "B.Fab")
		)
		(pad "1" smd circle
			(at 0.40005 0 90)
			(size 0 0)
			(layers "B.Cu" "B.Mask" "B.Paste")
			(net "V_DACB")
		)
		(pad "2" smd circle
			(at -0.40005 0 90)
			(size 0 0)
			(layers "B.Cu" "B.Mask" "B.Paste")
			(net "GND")
		)
	)
	(footprint ""
		(layer "B.Cu")
		(at 59.706256 -54.416198 -90)
		(property "Reference" "C130"
			(at 0 0 90)
			(layer "B.SilkS")
			(hide yes)
			(effects
				(font
					(size 1.27 1.27)
				)
				(justify mirror)
			)
		)
		(property "Value" ""
			(at 0 0 90)
			(layer "B.Fab")
			(effects
				(font
					(size 1.27 1.27)
				)
				(justify mirror)
			)
		)
		(duplicate_pad_numbers_are_jumpers no)
		(fp_line
			(start -0.7874 0.4064)
			(end 0.7874 0.4064)
			(stroke
				(width 0.1524)
				(type default)
			)
			(layer "B.SilkS")
		)
		(fp_line
			(start 0.7874 0.4064)
			(end 0.7874 -0.4064)
			(stroke
				(width 0.1524)
				(type default)
			)
			(layer "B.SilkS")
		)
		(fp_line
			(start -0.7874 -0.4064)
			(end -0.7874 0.4064)
			(stroke
				(width 0.1524)
				(type default)
			)
			(layer "B.SilkS")
		)
		(fp_line
			(start 0.7874 -0.4064)
			(end -0.7874 -0.4064)
			(stroke
				(width 0.1524)
				(type default)
			)
			(layer "B.SilkS")
		)
		(fp_line
			(start -0.67945 0.3048)
			(end -0.120396 0.3048)
			(stroke
				(width 0.1)
				(type default)
			)
			(layer "B.Fab")
		)
		(fp_line
			(start -0.120396 0.3048)
			(end -0.120396 0.2794)
			(stroke
				(width 0.1)
				(type default)
			)
			(layer "B.Fab")
		)
		(fp_line
			(start 0.12065 0.3048)
			(end 0.67945 0.3048)
			(stroke
				(width 0.1)
				(type default)
			)
			(layer "B.Fab")
		)
		(fp_line
			(start 0.67945 0.3048)
			(end 0.67945 -0.305054)
			(stroke
				(width 0.1)
				(type default)
			)
			(layer "B.Fab")
		)
		(fp_line
			(start -0.120396 0.2794)
			(end 0.12065 0.2794)
			(stroke
				(width 0.1)
				(type default)
			)
			(layer "B.Fab")
		)
		(fp_line
			(start 0.12065 0.2794)
			(end 0.12065 0.3048)
			(stroke
				(width 0.1)
				(type default)
			)
			(layer "B.Fab")
		)
		(fp_line
			(start -0.12065 -0.2794)
			(end -0.12065 -0.3048)
			(stroke
				(width 0.1)
				(type default)
			)
			(layer "B.Fab")
		)
		(fp_line
			(start 0.12065 -0.2794)
			(end -0.12065 -0.2794)
			(stroke
				(width 0.1)
				(type default)
			)
			(layer "B.Fab")
		)
		(fp_line
			(start -0.67945 -0.3048)
			(end -0.67945 0.3048)
			(stroke
				(width 0.1)
				(type default)
			)
			(layer "B.Fab")
		)
		(fp_line
			(start -0.12065 -0.3048)
			(end -0.67945 -0.3048)
			(stroke
				(width 0.1)
				(type default)
			)
			(layer "B.Fab")
		)
		(fp_line
			(start 0.12065 -0.305054)
			(end 0.12065 -0.2794)
			(stroke
				(width 0.1)
				(type default)
			)
			(layer "B.Fab")
		)
		(fp_line
			(start 0.67945 -0.305054)
			(end 0.12065 -0.305054)
			(stroke
				(width 0.1)
				(type default)
			)
			(layer "B.Fab")
		)
		(pad "1" smd circle
			(at 0.40005 0 90)
			(size 0 0)
			(layers "B.Cu" "B.Mask" "B.Paste")
			(net "P1V8_STBY_DP_VCC18A")
		)
		(pad "2" smd circle
			(at -0.40005 0 90)
			(size 0 0)
			(layers "B.Cu" "B.Mask" "B.Paste")
			(net "GND")
		)
	)
	(footprint ""
		(layer "B.Cu")
		(at 46.355 -96.8248 90)
		(property "Reference" "C238"
			(at 0 0 90)
			(layer "B.SilkS")
			(hide yes)
			(effects
				(font
					(size 1.27 1.27)
				)
				(justify mirror)
			)
		)
		(property "Value" ""
			(at 0 0 90)
			(layer "B.Fab")
			(effects
				(font
					(size 1.27 1.27)
				)
				(justify mirror)
			)
		)
		(duplicate_pad_numbers_are_jumpers no)
		(fp_line
			(start 0.7874 -0.4064)
			(end -0.7874 -0.4064)
			(stroke
				(width 0.1524)
				(type default)
			)
			(layer "B.SilkS")
		)
		(fp_line
			(start -0.7874 -0.4064)
			(end -0.7874 0.4064)
			(stroke
				(width 0.1524)
				(type default)
			)
			(layer "B.SilkS")
		)
		(fp_line
			(start 0.7874 0.4064)
			(end 0.7874 -0.4064)
			(stroke
				(width 0.1524)
				(type default)
			)
			(layer "B.SilkS")
		)
		(fp_line
			(start -0.7874 0.4064)
			(end 0.7874 0.4064)
			(stroke
				(width 0.1524)
				(type default)
			)
			(layer "B.SilkS")
		)
		(fp_line
			(start 0.67945 -0.305054)
			(end 0.12065 -0.305054)
			(stroke
				(width 0.1)
				(type default)
			)
			(layer "B.Fab")
		)
		(fp_line
			(start 0.12065 -0.305054)
			(end 0.12065 -0.2794)
			(stroke
				(width 0.1)
				(type default)
			)
			(layer "B.Fab")
		)
		(fp_line
			(start -0.12065 -0.3048)
			(end -0.67945 -0.3048)
			(stroke
				(width 0.1)
				(type default)
			)
			(layer "B.Fab")
		)
		(fp_line
			(start -0.67945 -0.3048)
			(end -0.67945 0.3048)
			(stroke
				(width 0.1)
				(type default)
			)
			(layer "B.Fab")
		)
		(fp_line
			(start 0.12065 -0.2794)
			(end -0.12065 -0.2794)
			(stroke
				(width 0.1)
				(type default)
			)
			(layer "B.Fab")
		)
		(fp_line
			(start -0.12065 -0.2794)
			(end -0.12065 -0.3048)
			(stroke
				(width 0.1)
				(type default)
			)
			(layer "B.Fab")
		)
		(fp_line
			(start 0.12065 0.2794)
			(end 0.12065 0.3048)
			(stroke
				(width 0.1)
				(type default)
			)
			(layer "B.Fab")
		)
		(fp_line
			(start -0.120396 0.2794)
			(end 0.12065 0.2794)
			(stroke
				(width 0.1)
				(type default)
			)
			(layer "B.Fab")
		)
		(fp_line
			(start 0.67945 0.3048)
			(end 0.67945 -0.305054)
			(stroke
				(width 0.1)
				(type default)
			)
			(layer "B.Fab")
		)
		(fp_line
			(start 0.12065 0.3048)
			(end 0.67945 0.3048)
			(stroke
				(width 0.1)
				(type default)
			)
			(layer "B.Fab")
		)
		(fp_line
			(start -0.120396 0.3048)
			(end -0.120396 0.2794)
			(stroke
				(width 0.1)
				(type default)
			)
			(layer "B.Fab")
		)
		(fp_line
			(start -0.67945 0.3048)
			(end -0.120396 0.3048)
			(stroke
				(width 0.1)
				(type default)
			)
			(layer "B.Fab")
		)
		(pad "1" smd circle
			(at 0.40005 0 270)
			(size 0 0)
			(layers "B.Cu" "B.Mask" "B.Paste")
			(net "USB3_FPNL_TXP")
		)
		(pad "2" smd circle
			(at -0.40005 0 270)
			(size 0 0)
			(layers "B.Cu" "B.Mask" "B.Paste")
			(net "USB3_01_TXP_C")
		)
	)
	(footprint ""
		(layer "B.Cu")
		(at 26.543 -99.695 45)
		(property "Reference" "C286"
			(at 0 0 45)
			(layer "B.SilkS")
			(hide yes)
			(effects
				(font
					(size 1.27 1.27)
				)
				(justify mirror)
			)
		)
		(property "Value" ""
			(at 0 0 45)
			(layer "B.Fab")
			(effects
				(font
					(size 1.27 1.27)
				)
				(justify mirror)
			)
		)
		(duplicate_pad_numbers_are_jumpers no)
		(fp_line
			(start -0.787389 -0.406267)
			(end -0.787389 0.406267)
			(stroke
				(width 0.1524)
				(type default)
			)
			(layer "B.SilkS")
		)
		(fp_line
			(start -0.787389 0.406267)
			(end 0.787389 0.406267)
			(stroke
				(width 0.1524)
				(type default)
			)
			(layer "B.SilkS")
		)
		(fp_line
			(start 0.787389 -0.406267)
			(end -0.787389 -0.406267)
			(stroke
				(width 0.1524)
				(type default)
			)
			(layer "B.SilkS")
		)
		(fp_line
			(start 0.787389 0.406267)
			(end 0.787389 -0.406267)
			(stroke
				(width 0.1524)
				(type default)
			)
			(layer "B.SilkS")
		)
		(fp_line
			(start -0.679446 -0.30479)
			(end -0.679446 0.30479)
			(stroke
				(width 0.1)
				(type default)
			)
			(layer "B.Fab")
		)
		(fp_line
			(start -0.120515 -0.30479)
			(end -0.679446 -0.30479)
			(stroke
				(width 0.1)
				(type default)
			)
			(layer "B.Fab")
		)
		(fp_line
			(start -0.120695 -0.279466)
			(end -0.120515 -0.30479)
			(stroke
				(width 0.1)
				(type default)
			)
			(layer "B.Fab")
		)
		(fp_line
			(start -0.679446 0.30479)
			(end -0.120515 0.30479)
			(stroke
				(width 0.1)
				(type default)
			)
			(layer "B.Fab")
		)
		(fp_line
			(start 0.120695 -0.304969)
			(end 0.120695 -0.279466)
			(stroke
				(width 0.1)
				(type default)
			)
			(layer "B.Fab")
		)
		(fp_line
			(start 0.120695 -0.279466)
			(end -0.120695 -0.279466)
			(stroke
				(width 0.1)
				(type default)
			)
			(layer "B.Fab")
		)
		(fp_line
			(start -0.120335 0.279466)
			(end 0.120695 0.279466)
			(stroke
				(width 0.1)
				(type default)
			)
			(layer "B.Fab")
		)
		(fp_line
			(start -0.120515 0.30479)
			(end -0.120335 0.279466)
			(stroke
				(width 0.1)
				(type default)
			)
			(layer "B.Fab")
		)
		(fp_line
			(start 0.679446 -0.305149)
			(end 0.120695 -0.304969)
			(stroke
				(width 0.1)
				(type default)
			)
			(layer "B.Fab")
		)
		(fp_line
			(start 0.120695 0.279466)
			(end 0.120515 0.30479)
			(stroke
				(width 0.1)
				(type default)
			)
			(layer "B.Fab")
		)
		(fp_line
			(start 0.120515 0.30479)
			(end 0.679446 0.30479)
			(stroke
				(width 0.1)
				(type default)
			)
			(layer "B.Fab")
		)
		(fp_line
			(start 0.679446 0.30479)
			(end 0.679446 -0.305149)
			(stroke
				(width 0.1)
				(type default)
			)
			(layer "B.Fab")
		)
		(pad "1" smd circle
			(at 0.40005 0 225)
			(size 0 0)
			(layers "B.Cu" "B.Mask" "B.Paste")
			(net "PVCCA_AUX_PLD")
		)
		(pad "2" smd circle
			(at -0.40005 0 225)
			(size 0 0)
			(layers "B.Cu" "B.Mask" "B.Paste")
			(net "GND")
		)
	)
)
